FILE_TYPE = MULTI_PHYS_TABLE;

PART 'SN74AVC4T774PWR'

{========================================================================================}
:VALUE             | PART_TYPE | MATERIAL | PART_NUMBER    = STANDARD    | LIFECYCLE      | PART_NUMBER   | JEDEC_TYPE  | DESCRIPTION                            | MANUFTR | MANUF_PN          | RD_CMPLS_LVL | CMPLS_LVL | FROM_PJ       | CLASS | DIP_SMD | DATA                      | EE_CHECK_LIST | FP_ECN | PSL | CREATOR | STATUS | MSD | ESD_CDM | ESD_HBM | ESD_MM | PIN_LENGTH_SHORT_PIN | PIN_LENGTH_LONG_PIN | CREATEDAY  ;
{========================================================================================}
 'SN74AVC4T774PWR' | 'SMLF'    | 'IC'     | 'AL04T774K00'(!) = ''               | ''               | 'AL04T774K00' |'TSSOP16XC'| 'IC OTHER(16P) SN74AVC4T774PWR(TSSOP)' | 'TIC'   | 'SN74AVC4T774PWR' | 'EP(V1)'     | 'EP(V1)'  | 'T6MB-JOSEPH' | 'IC'  | ''      | 'TIC_SN74AVC4T774PWR.pdf' | ''            | ''     | ''  | ''      | ''     | ''  | ''      | ''      | ''     | ''                   | ''                  | '20160810'
 'SN74AVC4T774PWR' | 'SMLF'    | 'EMPTY'  | 'AL04T774K00'(!) = ''               | ''               | 'AL04T774K00' |'TSSOP16XC'| 'IC OTHER(16P) SN74AVC4T774PWR(TSSOP)' | 'TIC'   | 'SN74AVC4T774PWR' | 'EP(V1)'     | 'EP(V1)'  | 'T6MB-JOSEPH' | 'IC'  | ''      | 'TIC_SN74AVC4T774PWR.pdf' | ''            | ''     | ''  | ''      | ''     | ''  | ''      | ''      | ''     | ''                   | ''                  | '20160810'

END_PART

END.

